# S9S_MB_2U (Grand Teton) — schematic netlist excerpt (pin names and nets, part order shuffled) for the footprints in the layout excerpt that follows; sources: Cadence DE-HDL packaged netlist, KiCad conversion of 03242023_DA0F0TMBIJ0_F0T_Motherboard_J_brd_V01_OCP.brd

R4646  Q_RES  1K 1% EMPTY  pkg 0402LF  page 167 : A = FM_P2E_BUF2_EQB0 ; B = GND

Q57  MOSFET_NCH_1D3S  PSMNR58-30YLH IC  pkg SOT1023  page 260
  \1\  = P5V
  \2\  = P5V
  \3\  = P5V
  \4\  = VR_P5V_EN_D_R
  \5\  = P5V_AUX

(kicad_pcb
	(version 20260206)
	(generator "pcbnew")
	(generator_version "10.0")
	(general
		(thickness 1.6)
		(legacy_teardrops no)
	)
	(paper "A4")
	(title_block
		(title "03242023_DA0F0TMBIJ0_F0T_Motherboard_J_brd_V01_OCP.brd")
		(comment 1 "Grand Teton / footprints 961-962 of 6105")
	)
	(layers
		(0 "F.Cu" signal "TOP")
		(4 "In1.Cu" signal "GND")
		(6 "In2.Cu" signal "IN1")
		(8 "In3.Cu" signal "GND1")
		(10 "In4.Cu" signal "IN2")
		(12 "In5.Cu" signal "GND2")
		(14 "In6.Cu" signal "IN3")
		(16 "In7.Cu" signal "GND3")
		(18 "In8.Cu" signal "VCC")
		(20 "In9.Cu" signal "VCC1")
		(22 "In10.Cu" signal "GND4")
		(24 "In11.Cu" signal "IN4")
		(26 "In12.Cu" signal "GND5")
		(28 "In13.Cu" signal "IN5")
		(30 "In14.Cu" signal "GND6")
		(32 "In15.Cu" signal "IN6")
		(34 "In16.Cu" signal "GND7")
		(2 "B.Cu" signal "BOTTOM")
		(9 "F.Adhes" user "F.Adhesive")
		(11 "B.Adhes" user "B.Adhesive")
		(13 "F.Paste" user "Package Geometry/Pastemask Top")
		(15 "B.Paste" user "Package Geometry/Pastemask Bottom")
		(5 "F.SilkS" user "Ref Des/Silkscreen Top")
		(7 "B.SilkS" user "Ref Des/Silkscreen Bottom")
		(1 "F.Mask" user "Board Geometry/Soldermask Top")
		(3 "B.Mask" user "Board Geometry/Soldermask Bottom")
		(17 "Dwgs.User" user "User.Drawings")
		(19 "Cmts.User" user "User.Comments")
		(21 "Eco1.User" user "User.Eco1")
		(23 "Eco2.User" user "User.Eco2")
		(25 "Edge.Cuts" user "Board Geometry/Outline")
		(27 "Margin" user)
		(31 "F.CrtYd" user "Package Geometry/Place Bound Top")
		(29 "B.CrtYd" user "Package Geometry/Place Bound Bottom")
		(35 "F.Fab" user "Ref Des/Assembly Top")
		(33 "B.Fab" user "Ref Des/Assembly Bottom")
	)
	(footprint ""
		(layer "F.Cu")
		(at 46.096428 -390.007348)
		(property "Reference" "R4646"
			(at 0 0 0)
			(layer "F.SilkS")
			(hide yes)
			(effects
				(font
					(size 1.27 1.27)
				)
			)
		)
		(property "Value" ""
			(at 0 0 0)
			(layer "F.Fab")
			(effects
				(font
					(size 1.27 1.27)
				)
			)
		)
		(duplicate_pad_numbers_are_jumpers no)
		(fp_line
			(start -0.7874 -0.4064)
			(end 0.7874 -0.4064)
			(stroke
				(width 0.1524)
				(type default)
			)
			(layer "F.SilkS")
		)
		(fp_line
			(start -0.7874 0.4064)
			(end -0.7874 -0.4064)
			(stroke
				(width 0.1524)
				(type default)
			)
			(layer "F.SilkS")
		)
		(fp_line
			(start 0.7874 -0.4064)
			(end 0.7874 0.4064)
			(stroke
				(width 0.1524)
				(type default)
			)
			(layer "F.SilkS")
		)
		(fp_line
			(start 0.7874 0.4064)
			(end -0.7874 0.4064)
			(stroke
				(width 0.1524)
				(type default)
			)
			(layer "F.SilkS")
		)
		(fp_line
			(start -0.67945 -0.305054)
			(end -0.12065 -0.305054)
			(stroke
				(width 0.1)
				(type default)
			)
			(layer "F.Fab")
		)
		(fp_line
			(start -0.67945 0.3048)
			(end -0.67945 -0.305054)
			(stroke
				(width 0.1)
				(type default)
			)
			(layer "F.Fab")
		)
		(fp_line
			(start -0.12065 -0.305054)
			(end -0.12065 -0.2794)
			(stroke
				(width 0.1)
				(type default)
			)
			(layer "F.Fab")
		)
		(fp_line
			(start -0.12065 -0.2794)
			(end 0.12065 -0.2794)
			(stroke
				(width 0.1)
				(type default)
			)
			(layer "F.Fab")
		)
		(fp_line
			(start -0.12065 0.2794)
			(end -0.12065 0.3048)
			(stroke
				(width 0.1)
				(type default)
			)
			(layer "F.Fab")
		)
		(fp_line
			(start -0.12065 0.3048)
			(end -0.67945 0.3048)
			(stroke
				(width 0.1)
				(type default)
			)
			(layer "F.Fab")
		)
		(fp_line
			(start 0.120396 0.2794)
			(end -0.12065 0.2794)
			(stroke
				(width 0.1)
				(type default)
			)
			(layer "F.Fab")
		)
		(fp_line
			(start 0.120396 0.3048)
			(end 0.120396 0.2794)
			(stroke
				(width 0.1)
				(type default)
			)
			(layer "F.Fab")
		)
		(fp_line
			(start 0.12065 -0.3048)
			(end 0.67945 -0.3048)
			(stroke
				(width 0.1)
				(type default)
			)
			(layer "F.Fab")
		)
		(fp_line
			(start 0.12065 -0.2794)
			(end 0.12065 -0.3048)
			(stroke
				(width 0.1)
				(type default)
			)
			(layer "F.Fab")
		)
		(fp_line
			(start 0.67945 -0.3048)
			(end 0.67945 0.3048)
			(stroke
				(width 0.1)
				(type default)
			)
			(layer "F.Fab")
		)
		(fp_line
			(start 0.67945 0.3048)
			(end 0.120396 0.3048)
			(stroke
				(width 0.1)
				(type default)
			)
			(layer "F.Fab")
		)
		(pad "1" smd circle
			(at -0.40005 0)
			(size 0 0)
			(layers "F.Cu" "F.Mask" "F.Paste")
			(net "FM_P2E_BUF2_EQB0")
		)
		(pad "2" smd circle
			(at 0.40005 0)
			(size 0 0)
			(layers "F.Cu" "F.Mask" "F.Paste")
			(net "GND")
		)
	)
	(footprint ""
		(layer "F.Cu")
		(at 441.353194 -375.662698 90)
		(property "Reference" "Q57"
			(at -0.4699 -6.276594 0)
			(unlocked yes)
			(layer "F.SilkS")
			(effects
				(font
					(size 0.7874 0.5842)
					(thickness 0.1524)
				)
				(justify left)
			)
		)
		(property "Value" ""
			(at 0 0 90)
			(layer "F.Fab")
			(effects
				(font
					(size 1.27 1.27)
				)
			)
		)
		(duplicate_pad_numbers_are_jumpers no)
		(fp_line
			(start 2.350008 -2.649982)
			(end 2.350008 -2.4892)
			(stroke
				(width 0.1524)
				(type default)
			)
			(layer "F.SilkS")
		)
		(fp_line
			(start -2.350008 -2.649982)
			(end 2.350008 -2.649982)
			(stroke
				(width 0.1524)
				(type default)
			)
			(layer "F.SilkS")
		)
		(fp_line
			(start -2.350008 -2.4384)
			(end -2.350008 -2.649982)
			(stroke
				(width 0.1524)
				(type default)
			)
			(layer "F.SilkS")
		)
		(fp_line
			(start 2.350008 2.4892)
			(end 2.350008 2.649982)
			(stroke
				(width 0.1524)
				(type default)
			)
			(layer "F.SilkS")
		)
		(fp_line
			(start 2.350008 2.649982)
			(end -2.350008 2.649982)
			(stroke
				(width 0.1524)
				(type default)
			)
			(layer "F.SilkS")
		)
		(fp_line
			(start -2.350008 2.649982)
			(end -2.350008 2.413)
			(stroke
				(width 0.1524)
				(type default)
			)
			(layer "F.SilkS")
		)
		(fp_poly
			(pts
				(xy -4.441444 -2.00914) (xy -5.482844 -1.62814) (xy -5.482844 -2.42824)
			)
			(stroke
				(width 0)
				(type default)
			)
			(fill yes)
			(layer "F.SilkS")
		)
		(fp_line
			(start 2.350008 -2.649982)
			(end 2.350008 2.649982)
			(stroke
				(width 0.1)
				(type default)
			)
			(layer "F.Fab")
		)
		(fp_line
			(start -2.350008 -2.649982)
			(end 2.350008 -2.649982)
			(stroke
				(width 0.1)
				(type default)
			)
			(layer "F.Fab")
		)
		(fp_line
			(start 2.350008 2.649982)
			(end -2.350008 2.649982)
			(stroke
				(width 0.1)
				(type default)
			)
			(layer "F.Fab")
		)
		(fp_line
			(start -2.350008 2.649982)
			(end -2.350008 -2.649982)
			(stroke
				(width 0.1)
				(type default)
			)
			(layer "F.Fab")
		)
		(fp_poly
			(pts
				(xy -3.717544 -1.905) (xy -4.758944 -2.3241) (xy -4.758944 -1.524)
			)
			(stroke
				(width 0)
				(type default)
			)
			(fill yes)
			(layer "F.Fab")
		)
		(pad "1" smd rect
			(at -2.999994 -1.905)
			(size 0.7112 1.1684)
			(layers "F.Cu" "F.Mask" "F.Paste")
			(net "P5V")
		)
		(pad "2" smd rect
			(at -2.999994 -0.635)
			(size 0.7112 1.1684)
			(layers "F.Cu" "F.Mask" "F.Paste")
			(net "P5V")
		)
		(pad "3" smd rect
			(at -2.999994 0.635)
			(size 0.7112 1.1684)
			(layers "F.Cu" "F.Mask" "F.Paste")
			(net "P5V")
		)
		(pad "4" smd rect
			(at -2.999994 1.905)
			(size 0.7112 1.1684)
			(layers "F.Cu" "F.Mask" "F.Paste")
			(net "VR_P5V_EN_D_R")
		)
		(pad "5" smd circle
			(at 0.925068 0)
			(size 0 0)
			(layers "F.Cu" "F.Mask" "F.Paste")
			(net "P5V_AUX")
		)
		(zone
			(layer "F.Cu")
			(hatch none 0.5)
			(connect_pads
				(clearance 0)
			)
			(min_thickness 0.25)
			(keepout
				(tracks not_allowed)
				(vias allowed)
				(pads allowed)
				(copperpour not_allowed)
				(footprints allowed)
			)
			(placement
				(enabled no)
				(sheetname "")
			)
			(fill
				(thermal_gap 0.5)
				(thermal_bridge_width 0.5)
				(island_removal_mode 0)
			)
			(polygon
				(pts
					(xy 439.194194 -374.272048) (xy 439.194194 -374.214898) (xy 443.512194 -374.214898) (xy 443.512194 -374.277128)
					(xy 443.994794 -374.277128) (xy 443.994794 -373.313198) (xy 438.711594 -373.313198) (xy 438.711594 -374.272048)
				)
			)
		)
	)
)
